(kicad_pcb
	(version 20260206)
	(generator "pcbnew")
	(generator_version "10.0")
	(general
		(thickness 1.6)
		(legacy_teardrops no)
	)
	(paper "A4")
	(title_block
		(title "03242023_DA0F0TMBIJ0_F0T_Motherboard_J_brd_V01_OCP.brd")
		(comment 1 "Grand Teton / footprints 1622-1627 of 6105")
	)
	(layers
		(0 "F.Cu" signal "TOP")
		(4 "In1.Cu" signal "GND")
		(6 "In2.Cu" signal "IN1")
		(8 "In3.Cu" signal "GND1")
		(10 "In4.Cu" signal "IN2")
		(12 "In5.Cu" signal "GND2")
		(14 "In6.Cu" signal "IN3")
		(16 "In7.Cu" signal "GND3")
		(18 "In8.Cu" signal "VCC")
		(20 "In9.Cu" signal "VCC1")
		(22 "In10.Cu" signal "GND4")
		(24 "In11.Cu" signal "IN4")
		(26 "In12.Cu" signal "GND5")
		(28 "In13.Cu" signal "IN5")
		(30 "In14.Cu" signal "GND6")
		(32 "In15.Cu" signal "IN6")
		(34 "In16.Cu" signal "GND7")
		(2 "B.Cu" signal "BOTTOM")
		(9 "F.Adhes" user "F.Adhesive")
		(11 "B.Adhes" user "B.Adhesive")
		(13 "F.Paste" user "Package Geometry/Pastemask Top")
		(15 "B.Paste" user "Package Geometry/Pastemask Bottom")
		(5 "F.SilkS" user "Ref Des/Silkscreen Top")
		(7 "B.SilkS" user "Ref Des/Silkscreen Bottom")
		(1 "F.Mask" user "Board Geometry/Soldermask Top")
		(3 "B.Mask" user "Board Geometry/Soldermask Bottom")
		(17 "Dwgs.User" user "User.Drawings")
		(19 "Cmts.User" user "User.Comments")
		(21 "Eco1.User" user "User.Eco1")
		(23 "Eco2.User" user "User.Eco2")
		(25 "Edge.Cuts" user "Board Geometry/Outline")
		(27 "Margin" user)
		(31 "F.CrtYd" user "Package Geometry/Place Bound Top")
		(29 "B.CrtYd" user "Package Geometry/Place Bound Bottom")
		(35 "F.Fab" user "Ref Des/Assembly Top")
		(33 "B.Fab" user "Ref Des/Assembly Bottom")
	)
	(footprint ""
		(layer "F.Cu")
		(at 432.38928 -136.644888 90)
		(property "Reference" "R2322"
			(at 0 0 90)
			(layer "F.SilkS")
			(hide yes)
			(effects
				(font
					(size 1.27 1.27)
				)
			)
		)
		(property "Value" ""
			(at 0 0 90)
			(layer "F.Fab")
			(effects
				(font
					(size 1.27 1.27)
				)
			)
		)
		(duplicate_pad_numbers_are_jumpers no)
		(fp_line
			(start 0.7874 -0.4064)
			(end 0.7874 0.4064)
			(stroke
				(width 0.1524)
				(type default)
			)
			(layer "F.SilkS")
		)
		(fp_line
			(start -0.7874 -0.4064)
			(end 0.7874 -0.4064)
			(stroke
				(width 0.1524)
				(type default)
			)
			(layer "F.SilkS")
		)
		(fp_line
			(start 0.7874 0.4064)
			(end -0.7874 0.4064)
			(stroke
				(width 0.1524)
				(type default)
			)
			(layer "F.SilkS")
		)
		(fp_line
			(start -0.7874 0.4064)
			(end -0.7874 -0.4064)
			(stroke
				(width 0.1524)
				(type default)
			)
			(layer "F.SilkS")
		)
		(fp_line
			(start -0.12065 -0.305054)
			(end -0.12065 -0.2794)
			(stroke
				(width 0.1)
				(type default)
			)
			(layer "F.Fab")
		)
		(fp_line
			(start -0.67945 -0.305054)
			(end -0.12065 -0.305054)
			(stroke
				(width 0.1)
				(type default)
			)
			(layer "F.Fab")
		)
		(fp_line
			(start 0.67945 -0.3048)
			(end 0.67945 0.3048)
			(stroke
				(width 0.1)
				(type default)
			)
			(layer "F.Fab")
		)
		(fp_line
			(start 0.12065 -0.3048)
			(end 0.67945 -0.3048)
			(stroke
				(width 0.1)
				(type default)
			)
			(layer "F.Fab")
		)
		(fp_line
			(start 0.12065 -0.2794)
			(end 0.12065 -0.3048)
			(stroke
				(width 0.1)
				(type default)
			)
			(layer "F.Fab")
		)
		(fp_line
			(start -0.12065 -0.2794)
			(end 0.12065 -0.2794)
			(stroke
				(width 0.1)
				(type default)
			)
			(layer "F.Fab")
		)
		(fp_line
			(start 0.120396 0.2794)
			(end -0.12065 0.2794)
			(stroke
				(width 0.1)
				(type default)
			)
			(layer "F.Fab")
		)
		(fp_line
			(start -0.12065 0.2794)
			(end -0.12065 0.3048)
			(stroke
				(width 0.1)
				(type default)
			)
			(layer "F.Fab")
		)
		(fp_line
			(start 0.67945 0.3048)
			(end 0.120396 0.3048)
			(stroke
				(width 0.1)
				(type default)
			)
			(layer "F.Fab")
		)
		(fp_line
			(start 0.120396 0.3048)
			(end 0.120396 0.2794)
			(stroke
				(width 0.1)
				(type default)
			)
			(layer "F.Fab")
		)
		(fp_line
			(start -0.12065 0.3048)
			(end -0.67945 0.3048)
			(stroke
				(width 0.1)
				(type default)
			)
			(layer "F.Fab")
		)
		(fp_line
			(start -0.67945 0.3048)
			(end -0.67945 -0.305054)
			(stroke
				(width 0.1)
				(type default)
			)
			(layer "F.Fab")
		)
		(pad "1" smd circle
			(at -0.40005 0 90)
			(size 0 0)
			(layers "F.Cu" "F.Mask" "F.Paste")
			(net "PVNN_TERM_CPU0")
		)
		(pad "2" smd circle
			(at 0.40005 0 90)
			(size 0 0)
			(layers "F.Cu" "F.Mask" "F.Paste")
			(net "SVID_CLK0_CPU0_R")
		)
	)
	(footprint ""
		(layer "F.Cu")
		(at 249.28703 -44.979082 90)
		(property "Reference" "PR3962"
			(at 0 0 90)
			(layer "F.SilkS")
			(hide yes)
			(effects
				(font
					(size 1.27 1.27)
				)
			)
		)
		(property "Value" ""
			(at 0 0 90)
			(layer "F.Fab")
			(effects
				(font
					(size 1.27 1.27)
				)
			)
		)
		(duplicate_pad_numbers_are_jumpers no)
		(fp_line
			(start 0.7874 -0.4064)
			(end 0.7874 0.4064)
			(stroke
				(width 0.1524)
				(type default)
			)
			(layer "F.SilkS")
		)
		(fp_line
			(start -0.7874 -0.4064)
			(end 0.7874 -0.4064)
			(stroke
				(width 0.1524)
				(type default)
			)
			(layer "F.SilkS")
		)
		(fp_line
			(start 0.7874 0.4064)
			(end -0.7874 0.4064)
			(stroke
				(width 0.1524)
				(type default)
			)
			(layer "F.SilkS")
		)
		(fp_line
			(start -0.7874 0.4064)
			(end -0.7874 -0.4064)
			(stroke
				(width 0.1524)
				(type default)
			)
			(layer "F.SilkS")
		)
		(fp_line
			(start -0.12065 -0.305054)
			(end -0.12065 -0.2794)
			(stroke
				(width 0.1)
				(type default)
			)
			(layer "F.Fab")
		)
		(fp_line
			(start -0.67945 -0.305054)
			(end -0.12065 -0.305054)
			(stroke
				(width 0.1)
				(type default)
			)
			(layer "F.Fab")
		)
		(fp_line
			(start 0.67945 -0.3048)
			(end 0.67945 0.3048)
			(stroke
				(width 0.1)
				(type default)
			)
			(layer "F.Fab")
		)
		(fp_line
			(start 0.12065 -0.3048)
			(end 0.67945 -0.3048)
			(stroke
				(width 0.1)
				(type default)
			)
			(layer "F.Fab")
		)
		(fp_line
			(start 0.12065 -0.2794)
			(end 0.12065 -0.3048)
			(stroke
				(width 0.1)
				(type default)
			)
			(layer "F.Fab")
		)
		(fp_line
			(start -0.12065 -0.2794)
			(end 0.12065 -0.2794)
			(stroke
				(width 0.1)
				(type default)
			)
			(layer "F.Fab")
		)
		(fp_line
			(start 0.120396 0.2794)
			(end -0.12065 0.2794)
			(stroke
				(width 0.1)
				(type default)
			)
			(layer "F.Fab")
		)
		(fp_line
			(start -0.12065 0.2794)
			(end -0.12065 0.3048)
			(stroke
				(width 0.1)
				(type default)
			)
			(layer "F.Fab")
		)
		(fp_line
			(start 0.67945 0.3048)
			(end 0.120396 0.3048)
			(stroke
				(width 0.1)
				(type default)
			)
			(layer "F.Fab")
		)
		(fp_line
			(start 0.120396 0.3048)
			(end 0.120396 0.2794)
			(stroke
				(width 0.1)
				(type default)
			)
			(layer "F.Fab")
		)
		(fp_line
			(start -0.12065 0.3048)
			(end -0.67945 0.3048)
			(stroke
				(width 0.1)
				(type default)
			)
			(layer "F.Fab")
		)
		(fp_line
			(start -0.67945 0.3048)
			(end -0.67945 -0.305054)
			(stroke
				(width 0.1)
				(type default)
			)
			(layer "F.Fab")
		)
		(pad "1" smd circle
			(at -0.40005 0 90)
			(size 0 0)
			(layers "F.Cu" "F.Mask" "F.Paste")
			(net "P12V_E1S_OV_0")
		)
		(pad "2" smd circle
			(at 0.40005 0 90)
			(size 0 0)
			(layers "F.Cu" "F.Mask" "F.Paste")
			(net "GND")
		)
	)
	(footprint ""
		(layer "F.Cu")
		(at 50.98288 -434.812948 90)
		(property "Reference" "R2894"
			(at 0 0 90)
			(layer "F.SilkS")
			(hide yes)
			(effects
				(font
					(size 1.27 1.27)
				)
			)
		)
		(property "Value" ""
			(at 0 0 90)
			(layer "F.Fab")
			(effects
				(font
					(size 1.27 1.27)
				)
			)
		)
		(duplicate_pad_numbers_are_jumpers no)
		(fp_line
			(start 0.7874 -0.4064)
			(end 0.7874 0.4064)
			(stroke
				(width 0.1524)
				(type default)
			)
			(layer "F.SilkS")
		)
		(fp_line
			(start -0.7874 -0.4064)
			(end 0.7874 -0.4064)
			(stroke
				(width 0.1524)
				(type default)
			)
			(layer "F.SilkS")
		)
		(fp_line
			(start 0.7874 0.4064)
			(end -0.7874 0.4064)
			(stroke
				(width 0.1524)
				(type default)
			)
			(layer "F.SilkS")
		)
		(fp_line
			(start -0.7874 0.4064)
			(end -0.7874 -0.4064)
			(stroke
				(width 0.1524)
				(type default)
			)
			(layer "F.SilkS")
		)
		(fp_line
			(start -0.12065 -0.305054)
			(end -0.12065 -0.2794)
			(stroke
				(width 0.1)
				(type default)
			)
			(layer "F.Fab")
		)
		(fp_line
			(start -0.67945 -0.305054)
			(end -0.12065 -0.305054)
			(stroke
				(width 0.1)
				(type default)
			)
			(layer "F.Fab")
		)
		(fp_line
			(start 0.67945 -0.3048)
			(end 0.67945 0.3048)
			(stroke
				(width 0.1)
				(type default)
			)
			(layer "F.Fab")
		)
		(fp_line
			(start 0.12065 -0.3048)
			(end 0.67945 -0.3048)
			(stroke
				(width 0.1)
				(type default)
			)
			(layer "F.Fab")
		)
		(fp_line
			(start 0.12065 -0.2794)
			(end 0.12065 -0.3048)
			(stroke
				(width 0.1)
				(type default)
			)
			(layer "F.Fab")
		)
		(fp_line
			(start -0.12065 -0.2794)
			(end 0.12065 -0.2794)
			(stroke
				(width 0.1)
				(type default)
			)
			(layer "F.Fab")
		)
		(fp_line
			(start 0.120396 0.2794)
			(end -0.12065 0.2794)
			(stroke
				(width 0.1)
				(type default)
			)
			(layer "F.Fab")
		)
		(fp_line
			(start -0.12065 0.2794)
			(end -0.12065 0.3048)
			(stroke
				(width 0.1)
				(type default)
			)
			(layer "F.Fab")
		)
		(fp_line
			(start 0.67945 0.3048)
			(end 0.120396 0.3048)
			(stroke
				(width 0.1)
				(type default)
			)
			(layer "F.Fab")
		)
		(fp_line
			(start 0.120396 0.3048)
			(end 0.120396 0.2794)
			(stroke
				(width 0.1)
				(type default)
			)
			(layer "F.Fab")
		)
		(fp_line
			(start -0.12065 0.3048)
			(end -0.67945 0.3048)
			(stroke
				(width 0.1)
				(type default)
			)
			(layer "F.Fab")
		)
		(fp_line
			(start -0.67945 0.3048)
			(end -0.67945 -0.305054)
			(stroke
				(width 0.1)
				(type default)
			)
			(layer "F.Fab")
		)
		(pad "1" smd circle
			(at -0.40005 0 90)
			(size 0 0)
			(layers "F.Cu" "F.Mask" "F.Paste")
			(net "SMB_1_BMC_GPU_R_SDA")
		)
		(pad "2" smd circle
			(at 0.40005 0 90)
			(size 0 0)
			(layers "F.Cu" "F.Mask" "F.Paste")
			(net "SMB_1_BMC_GPU_BUF_R_SDA")
		)
	)
	(footprint ""
		(layer "F.Cu")
		(at 50.43551 -148.536914 180)
		(property "Reference" "PR1795"
			(at 0 0 180)
			(layer "F.SilkS")
			(hide yes)
			(effects
				(font
					(size 1.27 1.27)
				)
			)
		)
		(property "Value" ""
			(at 0 0 180)
			(layer "F.Fab")
			(effects
				(font
					(size 1.27 1.27)
				)
			)
		)
		(duplicate_pad_numbers_are_jumpers no)
		(fp_line
			(start 0.7874 0.4064)
			(end -0.7874 0.4064)
			(stroke
				(width 0.1524)
				(type default)
			)
			(layer "F.SilkS")
		)
		(fp_line
			(start 0.7874 -0.4064)
			(end 0.7874 0.4064)
			(stroke
				(width 0.1524)
				(type default)
			)
			(layer "F.SilkS")
		)
		(fp_line
			(start -0.7874 0.4064)
			(end -0.7874 -0.4064)
			(stroke
				(width 0.1524)
				(type default)
			)
			(layer "F.SilkS")
		)
		(fp_line
			(start -0.7874 -0.4064)
			(end 0.7874 -0.4064)
			(stroke
				(width 0.1524)
				(type default)
			)
			(layer "F.SilkS")
		)
		(fp_line
			(start 0.67945 0.3048)
			(end 0.120396 0.3048)
			(stroke
				(width 0.1)
				(type default)
			)
			(layer "F.Fab")
		)
		(fp_line
			(start 0.67945 -0.3048)
			(end 0.67945 0.3048)
			(stroke
				(width 0.1)
				(type default)
			)
			(layer "F.Fab")
		)
		(fp_line
			(start 0.12065 -0.2794)
			(end 0.12065 -0.3048)
			(stroke
				(width 0.1)
				(type default)
			)
			(layer "F.Fab")
		)
		(fp_line
			(start 0.12065 -0.3048)
			(end 0.67945 -0.3048)
			(stroke
				(width 0.1)
				(type default)
			)
			(layer "F.Fab")
		)
		(fp_line
			(start 0.120396 0.3048)
			(end 0.120396 0.2794)
			(stroke
				(width 0.1)
				(type default)
			)
			(layer "F.Fab")
		)
		(fp_line
			(start 0.120396 0.2794)
			(end -0.12065 0.2794)
			(stroke
				(width 0.1)
				(type default)
			)
			(layer "F.Fab")
		)
		(fp_line
			(start -0.12065 0.3048)
			(end -0.67945 0.3048)
			(stroke
				(width 0.1)
				(type default)
			)
			(layer "F.Fab")
		)
		(fp_line
			(start -0.12065 0.2794)
			(end -0.12065 0.3048)
			(stroke
				(width 0.1)
				(type default)
			)
			(layer "F.Fab")
		)
		(fp_line
			(start -0.12065 -0.2794)
			(end 0.12065 -0.2794)
			(stroke
				(width 0.1)
				(type default)
			)
			(layer "F.Fab")
		)
		(fp_line
			(start -0.12065 -0.305054)
			(end -0.12065 -0.2794)
			(stroke
				(width 0.1)
				(type default)
			)
			(layer "F.Fab")
		)
		(fp_line
			(start -0.67945 0.3048)
			(end -0.67945 -0.305054)
			(stroke
				(width 0.1)
				(type default)
			)
			(layer "F.Fab")
		)
		(fp_line
			(start -0.67945 -0.305054)
			(end -0.12065 -0.305054)
			(stroke
				(width 0.1)
				(type default)
			)
			(layer "F.Fab")
		)
		(pad "1" smd circle
			(at -0.40005 0 180)
			(size 0 0)
			(layers "F.Cu" "F.Mask" "F.Paste")
			(net "SW_PVCCINFAON_CPU1_BOOT2")
		)
		(pad "2" smd circle
			(at 0.40005 0 180)
			(size 0 0)
			(layers "F.Cu" "F.Mask" "F.Paste")
			(net "SW_PVCCINFAON_CPU1_BOOT2_R")
		)
	)
	(footprint ""
		(layer "F.Cu")
		(at 179.352448 -400.223482 180)
		(property "Reference" "PR1131"
			(at 0 0 180)
			(layer "F.SilkS")
			(hide yes)
			(effects
				(font
					(size 1.27 1.27)
				)
			)
		)
		(property "Value" ""
			(at 0 0 180)
			(layer "F.Fab")
			(effects
				(font
					(size 1.27 1.27)
				)
			)
		)
		(duplicate_pad_numbers_are_jumpers no)
		(fp_line
			(start 0.7874 0.4064)
			(end -0.7874 0.4064)
			(stroke
				(width 0.1524)
				(type default)
			)
			(layer "F.SilkS")
		)
		(fp_line
			(start 0.7874 -0.4064)
			(end 0.7874 0.4064)
			(stroke
				(width 0.1524)
				(type default)
			)
			(layer "F.SilkS")
		)
		(fp_line
			(start -0.7874 0.4064)
			(end -0.7874 -0.4064)
			(stroke
				(width 0.1524)
				(type default)
			)
			(layer "F.SilkS")
		)
		(fp_line
			(start -0.7874 -0.4064)
			(end 0.7874 -0.4064)
			(stroke
				(width 0.1524)
				(type default)
			)
			(layer "F.SilkS")
		)
		(fp_line
			(start 0.67945 0.3048)
			(end 0.120396 0.3048)
			(stroke
				(width 0.1)
				(type default)
			)
			(layer "F.Fab")
		)
		(fp_line
			(start 0.67945 -0.3048)
			(end 0.67945 0.3048)
			(stroke
				(width 0.1)
				(type default)
			)
			(layer "F.Fab")
		)
		(fp_line
			(start 0.12065 -0.2794)
			(end 0.12065 -0.3048)
			(stroke
				(width 0.1)
				(type default)
			)
			(layer "F.Fab")
		)
		(fp_line
			(start 0.12065 -0.3048)
			(end 0.67945 -0.3048)
			(stroke
				(width 0.1)
				(type default)
			)
			(layer "F.Fab")
		)
		(fp_line
			(start 0.120396 0.3048)
			(end 0.120396 0.2794)
			(stroke
				(width 0.1)
				(type default)
			)
			(layer "F.Fab")
		)
		(fp_line
			(start 0.120396 0.2794)
			(end -0.12065 0.2794)
			(stroke
				(width 0.1)
				(type default)
			)
			(layer "F.Fab")
		)
		(fp_line
			(start -0.12065 0.3048)
			(end -0.67945 0.3048)
			(stroke
				(width 0.1)
				(type default)
			)
			(layer "F.Fab")
		)
		(fp_line
			(start -0.12065 0.2794)
			(end -0.12065 0.3048)
			(stroke
				(width 0.1)
				(type default)
			)
			(layer "F.Fab")
		)
		(fp_line
			(start -0.12065 -0.2794)
			(end 0.12065 -0.2794)
			(stroke
				(width 0.1)
				(type default)
			)
			(layer "F.Fab")
		)
		(fp_line
			(start -0.12065 -0.305054)
			(end -0.12065 -0.2794)
			(stroke
				(width 0.1)
				(type default)
			)
			(layer "F.Fab")
		)
		(fp_line
			(start -0.67945 0.3048)
			(end -0.67945 -0.305054)
			(stroke
				(width 0.1)
				(type default)
			)
			(layer "F.Fab")
		)
		(fp_line
			(start -0.67945 -0.305054)
			(end -0.12065 -0.305054)
			(stroke
				(width 0.1)
				(type default)
			)
			(layer "F.Fab")
		)
		(pad "1" smd circle
			(at -0.40005 0 180)
			(size 0 0)
			(layers "F.Cu" "F.Mask" "F.Paste")
			(net "HSC_CS")
		)
		(pad "2" smd circle
			(at 0.40005 0 180)
			(size 0 0)
			(layers "F.Cu" "F.Mask" "F.Paste")
			(net "AGND_HSC")
		)
	)
	(footprint ""
		(layer "F.Cu")
		(at 417.83762 -48.53178 -90)
		(property "Reference" "U99"
			(at 3.965702 1.35382 0)
			(unlocked yes)
			(layer "F.SilkS")
			(effects
				(font
					(size 0.7874 0.5842)
					(thickness 0.1524)
				)
				(justify left)
			)
		)
		(property "Value" ""
			(at 0 0 270)
			(layer "F.Fab")
			(effects
				(font
					(size 1.27 1.27)
				)
			)
		)
		(duplicate_pad_numbers_are_jumpers no)
		(fp_line
			(start -1.934972 1.5494)
			(end -1.934972 -1.5494)
			(stroke
				(width 0.1524)
				(type default)
			)
			(layer "F.SilkS")
		)
		(fp_line
			(start 1.934972 1.5494)
			(end -1.934972 1.5494)
			(stroke
				(width 0.1524)
				(type default)
			)
			(layer "F.SilkS")
		)
		(fp_line
			(start -1.934972 -1.5494)
			(end 1.934972 -1.5494)
			(stroke
				(width 0.1524)
				(type default)
			)
			(layer "F.SilkS")
		)
		(fp_line
			(start 1.934972 -1.5494)
			(end 1.934972 1.5494)
			(stroke
				(width 0.1524)
				(type default)
			)
			(layer "F.SilkS")
		)
		(fp_line
			(start -0.901446 1.5494)
			(end -0.901446 -1.5494)
			(stroke
				(width 0.1)
				(type default)
			)
			(layer "F.Fab")
		)
		(fp_line
			(start 0.901446 1.5494)
			(end -0.901446 1.5494)
			(stroke
				(width 0.1)
				(type default)
			)
			(layer "F.Fab")
		)
		(fp_line
			(start -0.901446 -1.5494)
			(end 0.901446 -1.5494)
			(stroke
				(width 0.1)
				(type default)
			)
			(layer "F.Fab")
		)
		(fp_line
			(start 0.901446 -1.5494)
			(end 0.901446 1.5494)
			(stroke
				(width 0.1)
				(type default)
			)
			(layer "F.Fab")
		)
		(pad "1" smd rect
			(at -1.299972 -0.94996 180)
			(size 0.8128 1.016)
			(layers "F.Cu" "F.Mask" "F.Paste")
			(net "PWRGD_P5V")
		)
		(pad "2" smd rect
			(at -1.299972 0.94996 180)
			(size 0.8128 1.016)
			(layers "F.Cu" "F.Mask" "F.Paste")
			(net "GND")
		)
		(pad "3" smd rect
			(at 1.299972 0 180)
			(size 0.8128 1.016)
			(layers "F.Cu" "F.Mask" "F.Paste")
			(net "P5V")
		)
	)
)
